FILE_TYPE = CONNECTIVITY;
{Allegro Design Entry HDL 17.2-2016 S081 (4005846) 1/11/2022}
"PAGE_NUMBER" = 128;
0"NC";
1"GND\g";
2"GND\g";
3"RST_CPU1_DRAM_GH_PLD_N"CDS_PHYS_NET_NAME"RST_CPU0_DRAM_GH_PLD_N";
4"RST_CPU1_DRAM_CD_PLD_N"CDS_PHYS_NET_NAME"RST_CPU0_DRAM_CD_PLD_N";
5"RST_CPU1_DRAM_CD_N"CDS_PHYS_NET_NAME"RST_CPU0_DRAM_CD_N";
6"RST_CPU1_DRAM_EF_N"CDS_PHYS_NET_NAME"RST_CPU0_DRAM_EF_N";
7"RST_CPU1_DRAM_GH_N"CDS_PHYS_NET_NAME"RST_CPU0_DRAM_GH_N";
8"RST_CPU1_DRAM_AB_N";
9"RST_CPU0_DRAM_AB_N";
10"RST_CPU0_DRAM_CD_N"CDS_PHYS_NET_NAME"H_CPU1_MEMHOT_OUT_LVC1_R_N";
11"RST_CPU0_DRAM_EF_N"CDS_PHYS_NET_NAME"RST_CPU0_DRAM_AB_N";
12"RST_CPU0_DRAM_GH_N"CDS_PHYS_NET_NAME"RST_CPU0_DRAM_AB_N";
13"RST_CPU0_DRAM_CD_PLD_N"CDS_PHYS_NET_NAME"RST_CPU0_DRAM_AB_PLD_N";
14"RST_CPU0_DRAM_EF_PLD_N"CDS_PHYS_NET_NAME"RST_CPU0_DRAM_AB_PLD_N";
15"RST_CPU0_DRAM_GH_PLD_N"CDS_PHYS_NET_NAME"RST_CPU0_DRAM_AB_PLD_N";
16"RST_CPU1_DRAM_AB_PLD_N";
17"RST_CPU1_DRAM_EF_PLD_N"CDS_PHYS_NET_NAME"RST_CPU0_DRAM_EF_PLD_N";
18"RST_CPU0_DRAM_AB_PLD_N";
%"Q_RES"
"1","(-5325,3325)","0","pure_quanta","I10";
;
PART_NUMBER"CS00002JB13"
VALUE"0"
TOLERANCE"5%"
$LOCATION"R853"
PACK_TYPE"0402LF"
CDS_LIB"pure_quanta"
MATERIAL"CHIP"
WATTAGE"1/16W"
$LOCATION"R853"
CDS_LOCATION"R853"
$SEC"1"
CDS_SEC"1";
"B"
$PN"2"14;
"A"
$PN"1"11;
%"Q_RES"
"1","(-5325,3375)","0","pure_quanta","I11";
;
PART_NUMBER"CS00002JB13"
VALUE"0"
TOLERANCE"5%"
$LOCATION"R852"
PACK_TYPE"0402LF"
CDS_LIB"pure_quanta"
MATERIAL"CHIP"
WATTAGE"1/16W"
$LOCATION"R852"
CDS_LOCATION"R852"
$SEC"1"
CDS_SEC"1";
"B"
$PN"2"13;
"A"
$PN"1"10;
%"Q_RES"
"1","(-5325,3425)","0","pure_quanta","I12";
;
PART_NUMBER"CS00002JB13"
TOLERANCE"5%"
VALUE"0"
PACK_TYPE"0402LF"
WATTAGE"1/16W"
MATERIAL"CHIP"
$LOCATION"R851"
CDS_LIB"pure_quanta"
$LOCATION"R851"
CDS_LOCATION"R851"
$SEC"1"
CDS_SEC"1";
"B"
$PN"2"18;
"A"
$PN"1"9;
%"Q_RES"
"1","(-5325,425)","0","pure_quanta","I48";
;
PART_NUMBER"CS00002JB13"
TOLERANCE"5%"
VALUE"0"
$LOCATION"R861"
PACK_TYPE"0402LF"
CDS_LIB"pure_quanta"
MATERIAL"CHIP"
WATTAGE"1/16W"
$LOCATION"R861"
CDS_LOCATION"R861"
$SEC"1"
CDS_SEC"1";
"B"
$PN"2"17;
"A"
$PN"1"6;
%"Q_RES"
"1","(-5325,375)","0","pure_quanta","I49";
;
PART_NUMBER"CS00002JB13"
TOLERANCE"5%"
VALUE"0"
$LOCATION"R2969"
WATTAGE"1/16W"
MATERIAL"CHIP"
CDS_LIB"pure_quanta"
PACK_TYPE"0402LF"
CDS_LOCATION"R2969"
$SEC"1"
CDS_SEC"1";
"B"
$PN"2"3;
"A"
$PN"1"7;
%"Q_RES"
"1","(-5325,525)","0","pure_quanta","I50";
;
PART_NUMBER"CS00002JB13"
MATERIAL"CHIP"
PACK_TYPE"0402LF"
VALUE"0"
TOLERANCE"5%"
WATTAGE"1/16W"
$LOCATION"R859"
CDS_LIB"pure_quanta"
$LOCATION"R859"
CDS_LOCATION"R859"
$SEC"1"
CDS_SEC"1";
"B"
$PN"2"16;
"A"
$PN"1"8;
%"Q_RES"
"1","(-5325,475)","0","pure_quanta","I51";
;
PART_NUMBER"CS00002JB13"
TOLERANCE"5%"
VALUE"0"
$LOCATION"R860"
PACK_TYPE"0402LF"
CDS_LIB"pure_quanta"
MATERIAL"CHIP"
WATTAGE"1/16W"
$LOCATION"R860"
CDS_LOCATION"R860"
$SEC"1"
CDS_SEC"1";
"B"
$PN"2"4;
"A"
$PN"1"5;
%"Q_RES"
"2","(-6500,3000)","0","pure_quanta","I77";
;
PART_NUMBER"CS31002FB08"
VALUE"10K"
MATERIAL"CHIP"
TOLERANCE"1%"
WATTAGE"1/16W"
PACK_TYPE"0402LF"
$LOCATION"R938"
CDS_LIB"pure_quanta"
CDS_LOCATION"R938"
$SEC"1"
CDS_SEC"1";
"A"
$PN"1"12;
"B"
$PN"2"2;
%"Q_RES"
"2","(-6700,3000)","0","pure_quanta","I78";
;
PART_NUMBER"CS31002FB08"
VALUE"10K"
PACK_TYPE"0402LF"
WATTAGE"1/16W"
TOLERANCE"1%"
MATERIAL"CHIP"
$LOCATION"R936"
CDS_LIB"pure_quanta"
CDS_LOCATION"R936"
$SEC"1"
CDS_SEC"1";
"A"
$PN"1"11;
"B"
$PN"2"2;
%"Q_RES"
"2","(-6900,3000)","0","pure_quanta","I79";
;
PART_NUMBER"CS31002FB08"
VALUE"10K"
PACK_TYPE"0402LF"
WATTAGE"1/16W"
TOLERANCE"1%"
MATERIAL"CHIP"
$LOCATION"R934"
CDS_LIB"pure_quanta"
CDS_LOCATION"R934"
$SEC"1"
CDS_SEC"1";
"A"
$PN"1"10;
"B"
$PN"2"2;
%"Q_RES"
"2","(-7100,3000)","0","pure_quanta","I80";
;
PART_NUMBER"CS31002FB08"
VALUE"10K"
MATERIAL"CHIP"
TOLERANCE"1%"
WATTAGE"1/16W"
PACK_TYPE"0402LF"
$LOCATION"R932"
CDS_LIB"pure_quanta"
CDS_LOCATION"R932"
$SEC"1"
CDS_SEC"1";
"A"
$PN"1"9;
"B"
$PN"2"2;
%"UNIVERSAL_GND"
"1","(-6500,2675)","0","logical_power","I81";
;
CDS_LIB"logical_power"
HDL_POWER"GND";
"A"2;
%"Q_RES"
"2","(-7100,100)","0","pure_quanta","I82";
;
PART_NUMBER"CS31002FB08"
PACK_TYPE"0402LF"
WATTAGE"1/16W"
TOLERANCE"1%"
MATERIAL"CHIP"
VALUE"10K"
$LOCATION"R933"
CDS_LIB"pure_quanta"
CDS_LOCATION"R933"
$SEC"1"
CDS_SEC"1";
"A"
$PN"1"8;
"B"
$PN"2"1;
%"Q_RES"
"2","(-6500,100)","0","pure_quanta","I83";
;
PART_NUMBER"CS31002FB08"
VALUE"10K"
WATTAGE"1/16W"
PACK_TYPE"0402LF"
TOLERANCE"1%"
MATERIAL"CHIP"
$LOCATION"R939"
CDS_LIB"pure_quanta"
CDS_LOCATION"R939"
$SEC"1"
CDS_SEC"1";
"A"
$PN"1"7;
"B"
$PN"2"1;
%"UNIVERSAL_GND"
"1","(-6500,-225)","0","logical_power","I84";
;
CDS_LIB"logical_power"
HDL_POWER"GND";
"A"1;
%"Q_RES"
"2","(-6700,100)","0","pure_quanta","I85";
;
PART_NUMBER"CS31002FB08"
VALUE"10K"
WATTAGE"1/16W"
MATERIAL"CHIP"
TOLERANCE"1%"
PACK_TYPE"0402LF"
$LOCATION"R937"
CDS_LIB"pure_quanta"
CDS_LOCATION"R937"
$SEC"1"
CDS_SEC"1";
"A"
$PN"1"6;
"B"
$PN"2"1;
%"Q_RES"
"2","(-6900,100)","0","pure_quanta","I86";
;
PART_NUMBER"CS31002FB08"
VALUE"10K"
MATERIAL"CHIP"
TOLERANCE"1%"
WATTAGE"1/16W"
PACK_TYPE"0402LF"
$LOCATION"R935"
CDS_LIB"pure_quanta"
CDS_LOCATION"R935"
$SEC"1"
CDS_SEC"1";
"A"
$PN"1"5;
"B"
$PN"2"1;
%"Q_RES"
"1","(-5325,3275)","0","pure_quanta","I9";
;
PART_NUMBER"CS00002JB13"
VALUE"0"
TOLERANCE"5%"
$LOCATION"R854"
WATTAGE"1/16W"
MATERIAL"CHIP"
CDS_LIB"pure_quanta"
PACK_TYPE"0402LF"
$LOCATION"R854"
CDS_LOCATION"R854"
$SEC"1"
CDS_SEC"1";
"B"
$PN"2"15;
"A"
$PN"1"12;
END.
